# SCM (Grand Teton) — schematic netlist excerpt (pin names and nets, part order shuffled) for the footprints in the layout excerpt that follows; sources: Cadence DE-HDL packaged netlist, KiCad conversion of 12092022_DA0F0TMDCD0_F0T_Management_Board_D_brd_V3_OCP.brd

J5  SCONN11_9192031111LF  SCONN11_91920-31111LF IO  pkg CON_F11S2H2S_P1W4-22_LDH  page 46
  \1\  = SPI_SYS_R1_CLK
  \2\  = RST_PLTRST_TPM_N
  \3\  = SPI_SYS_R1_MOSI
  \4\  = SPI_SYS_R1_MISO
  \5\  = SPI_TPM_CS_N_R
  \6\  = SMB_PCH_TPM_SDA
  \7\  = P3V3_AUX
  \8\  = FM_TPM_PRSNT_0_N
  \9\  = IRQ_PCH_TPM_SPI_R_N
  \10\  = SMB_PCH_TPM_SCL
  \11\  = GND
  G1  = GND
  G2  = GND

(kicad_pcb
	(version 20260206)
	(generator "pcbnew")
	(generator_version "10.0")
	(general
		(thickness 1.6)
		(legacy_teardrops no)
	)
	(paper "A4")
	(title_block
		(title "12092022_DA0F0TMDCD0_F0T_Management_Board_D_brd_V3_OCP.brd")
		(comment 1 "Grand Teton / footprints 378-378 of 1440")
	)
	(layers
		(0 "F.Cu" signal "TOP")
		(4 "In1.Cu" signal "GND")
		(6 "In2.Cu" signal "IN1")
		(8 "In3.Cu" signal "GND1")
		(10 "In4.Cu" signal "IN2")
		(12 "In5.Cu" signal "VCC")
		(14 "In6.Cu" signal "VCC1")
		(16 "In7.Cu" signal "IN3")
		(18 "In8.Cu" signal "GND2")
		(20 "In9.Cu" signal "IN4")
		(22 "In10.Cu" signal "GND3")
		(2 "B.Cu" signal "BOTTOM")
		(9 "F.Adhes" user "F.Adhesive")
		(11 "B.Adhes" user "B.Adhesive")
		(13 "F.Paste" user "Package Geometry/Pastemask Top")
		(15 "B.Paste" user "Package Geometry/Pastemask Bottom")
		(5 "F.SilkS" user "Ref Des/Silkscreen Top")
		(7 "B.SilkS" user "Ref Des/Silkscreen Bottom")
		(1 "F.Mask" user "Board Geometry/Soldermask Top")
		(3 "B.Mask" user "Board Geometry/Soldermask Bottom")
		(17 "Dwgs.User" user "User.Drawings")
		(19 "Cmts.User" user "User.Comments")
		(21 "Eco1.User" user "User.Eco1")
		(23 "Eco2.User" user "User.Eco2")
		(25 "Edge.Cuts" user "Board Geometry/Outline")
		(27 "Margin" user)
		(31 "F.CrtYd" user "Package Geometry/Place Bound Top")
		(29 "B.CrtYd" user "Package Geometry/Place Bound Bottom")
		(35 "F.Fab" user "Ref Des/Assembly Top")
		(33 "B.Fab" user "Ref Des/Assembly Bottom")
	)
	(footprint ""
		(layer "F.Cu")
		(at 62.701932 -94.856046 180)
		(property "Reference" "J5"
			(at -3.414268 -4.217416 0)
			(unlocked yes)
			(layer "F.SilkS")
			(effects
				(font
					(size 0.7874 0.5842)
					(thickness 0.1524)
				)
				(justify left)
			)
		)
		(property "Value" ""
			(at 0 0 180)
			(layer "F.Fab")
			(effects
				(font
					(size 1.27 1.27)
				)
			)
		)
		(duplicate_pad_numbers_are_jumpers no)
		(fp_line
			(start 2.500122 5.150104)
			(end -2.500122 5.150104)
			(stroke
				(width 0.1524)
				(type default)
			)
			(layer "F.SilkS")
		)
		(fp_line
			(start 2.500122 5.08)
			(end 2.500122 5.150104)
			(stroke
				(width 0.1524)
				(type default)
			)
			(layer "F.SilkS")
		)
		(fp_line
			(start 2.500122 2.4384)
			(end 2.500122 3.3782)
			(stroke
				(width 0.1524)
				(type default)
			)
			(layer "F.SilkS")
		)
		(fp_line
			(start 2.500122 -3.3782)
			(end 2.500122 -2.4384)
			(stroke
				(width 0.1524)
				(type default)
			)
			(layer "F.SilkS")
		)
		(fp_line
			(start 2.500122 -5.150104)
			(end 2.500122 -5.08)
			(stroke
				(width 0.1524)
				(type default)
			)
			(layer "F.SilkS")
		)
		(fp_line
			(start -2.500122 5.150104)
			(end -2.500122 5.08)
			(stroke
				(width 0.1524)
				(type default)
			)
			(layer "F.SilkS")
		)
		(fp_line
			(start -2.500122 3.3782)
			(end -2.500122 2.9464)
			(stroke
				(width 0.1524)
				(type default)
			)
			(layer "F.SilkS")
		)
		(fp_line
			(start -2.500122 -2.9464)
			(end -2.500122 -3.3782)
			(stroke
				(width 0.1524)
				(type default)
			)
			(layer "F.SilkS")
		)
		(fp_line
			(start -2.500122 -5.08)
			(end -2.500122 -5.150104)
			(stroke
				(width 0.1524)
				(type default)
			)
			(layer "F.SilkS")
		)
		(fp_line
			(start -2.500122 -5.150104)
			(end 2.500122 -5.150104)
			(stroke
				(width 0.1524)
				(type default)
			)
			(layer "F.SilkS")
		)
		(fp_poly
			(pts
				(xy -4.0894 -1.992122) (xy -4.0894 -3.008122) (xy -3.0734 -2.500122)
			)
			(stroke
				(width 0)
				(type default)
			)
			(fill yes)
			(layer "F.SilkS")
		)
		(fp_line
			(start 2.500122 5.150104)
			(end 2.500122 -5.150104)
			(stroke
				(width 0.1)
				(type default)
			)
			(layer "F.Fab")
		)
		(fp_line
			(start 2.500122 -5.150104)
			(end -2.500122 -5.150104)
			(stroke
				(width 0.1)
				(type default)
			)
			(layer "F.Fab")
		)
		(fp_line
			(start -2.500122 5.150104)
			(end 2.500122 5.150104)
			(stroke
				(width 0.1)
				(type default)
			)
			(layer "F.Fab")
		)
		(fp_line
			(start -2.500122 -5.150104)
			(end -2.500122 5.150104)
			(stroke
				(width 0.1)
				(type default)
			)
			(layer "F.Fab")
		)
		(fp_poly
			(pts
				(xy -4.0894 -1.992122) (xy -4.0894 -3.008122) (xy -3.0734 -2.500122)
			)
			(stroke
				(width 0)
				(type default)
			)
			(fill yes)
			(layer "F.Fab")
		)
		(fp_text user "11"
			(at 4.002532 3.224784 0)
			(unlocked yes)
			(layer "F.SilkS")
			(effects
				(font
					(size 0.7874 0.5842)
					(thickness 0.1524)
				)
			)
		)
		(fp_text user "7"
			(at 3.646932 -2.134616 0)
			(unlocked yes)
			(layer "F.SilkS")
			(effects
				(font
					(size 0.7874 0.5842)
					(thickness 0.1524)
				)
			)
		)
		(fp_text user "6"
			(at -3.592068 2.668524 180)
			(unlocked yes)
			(layer "F.SilkS")
			(effects
				(font
					(size 0.7874 0.5842)
					(thickness 0.1524)
				)
			)
		)
		(fp_text user "7"
			(at 3.520948 -2.048002 90)
			(unlocked yes)
			(layer "F.Fab")
			(effects
				(font
					(size 0.7874 0.5842)
					(thickness 0.1524)
				)
			)
		)
		(fp_text user "11"
			(at 3.495548 2.028444 90)
			(unlocked yes)
			(layer "F.Fab")
			(effects
				(font
					(size 0.7874 0.5842)
					(thickness 0.1524)
				)
			)
		)
		(fp_text user "6"
			(at -3.591052 2.574798 90)
			(unlocked yes)
			(layer "F.Fab")
			(effects
				(font
					(size 0.7874 0.5842)
					(thickness 0.1524)
				)
			)
		)
		(pad "1" smd rect
			(at -2.109978 -2.500122 270)
			(size 0.6096 1.651)
			(layers "F.Cu" "F.Mask" "F.Paste")
			(net "SPI_SYS_R1_CLK")
		)
		(pad "2" smd rect
			(at -2.109978 -1.500124 270)
			(size 0.6096 1.651)
			(layers "F.Cu" "F.Mask" "F.Paste")
			(net "RST_PLTRST_TPM_N")
		)
		(pad "3" smd rect
			(at -2.109978 -0.499872 270)
			(size 0.6096 1.651)
			(layers "F.Cu" "F.Mask" "F.Paste")
			(net "SPI_SYS_R1_MOSI")
		)
		(pad "4" smd rect
			(at -2.109978 0.499872 270)
			(size 0.6096 1.651)
			(layers "F.Cu" "F.Mask" "F.Paste")
			(net "SPI_SYS_R1_MISO")
		)
		(pad "5" smd rect
			(at -2.109978 1.500124 270)
			(size 0.6096 1.651)
			(layers "F.Cu" "F.Mask" "F.Paste")
			(net "SPI_TPM_CS_N_R")
		)
		(pad "6" smd rect
			(at -2.109978 2.500122 270)
			(size 0.6096 1.651)
			(layers "F.Cu" "F.Mask" "F.Paste")
			(net "SMB_PCH_TPM_SDA")
		)
		(pad "7" smd rect
			(at 2.109978 -1.999996 90)
			(size 0.6096 1.651)
			(layers "F.Cu" "F.Mask" "F.Paste")
			(net "P3V3_AUX")
		)
		(pad "8" smd rect
			(at 2.109978 -0.999998 90)
			(size 0.6096 1.651)
			(layers "F.Cu" "F.Mask" "F.Paste")
			(net "FM_TPM_PRSNT_0_N")
		)
		(pad "9" smd rect
			(at 2.109978 0 90)
			(size 0.6096 1.651)
			(layers "F.Cu" "F.Mask" "F.Paste")
			(net "IRQ_PCH_TPM_SPI_R_N")
		)
		(pad "10" smd rect
			(at 2.109978 0.999998 90)
			(size 0.6096 1.651)
			(layers "F.Cu" "F.Mask" "F.Paste")
			(net "SMB_PCH_TPM_SCL")
		)
		(pad "11" smd rect
			(at 2.109978 1.999996 90)
			(size 0.6096 1.651)
			(layers "F.Cu" "F.Mask" "F.Paste")
			(net "GND")
		)
		(pad "G1" smd rect
			(at 0 -4.219956 270)
			(size 1.4224 5.8674)
			(layers "F.Cu" "F.Mask" "F.Paste")
			(net "GND")
		)
		(pad "G2" smd rect
			(at 0 4.219956 90)
			(size 1.4224 5.8674)
			(layers "F.Cu" "F.Mask" "F.Paste")
			(net "GND")
		)
	)
)
